# S9S_MB_2U (Grand Teton) — schematic netlist excerpt (pin names and nets, part order shuffled) for the footprints in the layout excerpt that follows; sources: Cadence DE-HDL packaged netlist, KiCad conversion of 03242023_DA0F0TMBIJ0_F0T_Motherboard_J_brd_V01_OCP.brd

PR704  Q_RES  0 5% EMPTY  pkg 0402LF  page 289 : A = P3V3 ; B = PVCCFA_EHV_FIVRA_CPU1_PVCC2
C1757  Q_CAP  0.1UF 25V 10% EMPTY  pkg 0402  page 250 : A = P3V3_MAX11617_VDD ; B = GND

(kicad_pcb
	(version 20260206)
	(generator "pcbnew")
	(generator_version "10.0")
	(general
		(thickness 1.6)
		(legacy_teardrops no)
	)
	(paper "A4")
	(title_block
		(title "03242023_DA0F0TMBIJ0_F0T_Motherboard_J_brd_V01_OCP.brd")
		(comment 1 "Grand Teton / footprints 3096-3097 of 6105")
	)
	(layers
		(0 "F.Cu" signal "TOP")
		(4 "In1.Cu" signal "GND")
		(6 "In2.Cu" signal "IN1")
		(8 "In3.Cu" signal "GND1")
		(10 "In4.Cu" signal "IN2")
		(12 "In5.Cu" signal "GND2")
		(14 "In6.Cu" signal "IN3")
		(16 "In7.Cu" signal "GND3")
		(18 "In8.Cu" signal "VCC")
		(20 "In9.Cu" signal "VCC1")
		(22 "In10.Cu" signal "GND4")
		(24 "In11.Cu" signal "IN4")
		(26 "In12.Cu" signal "GND5")
		(28 "In13.Cu" signal "IN5")
		(30 "In14.Cu" signal "GND6")
		(32 "In15.Cu" signal "IN6")
		(34 "In16.Cu" signal "GND7")
		(2 "B.Cu" signal "BOTTOM")
		(9 "F.Adhes" user "F.Adhesive")
		(11 "B.Adhes" user "B.Adhesive")
		(13 "F.Paste" user "Package Geometry/Pastemask Top")
		(15 "B.Paste" user "Package Geometry/Pastemask Bottom")
		(5 "F.SilkS" user "Ref Des/Silkscreen Top")
		(7 "B.SilkS" user "Ref Des/Silkscreen Bottom")
		(1 "F.Mask" user "Board Geometry/Soldermask Top")
		(3 "B.Mask" user "Board Geometry/Soldermask Bottom")
		(17 "Dwgs.User" user "User.Drawings")
		(19 "Cmts.User" user "User.Comments")
		(21 "Eco1.User" user "User.Eco1")
		(23 "Eco2.User" user "User.Eco2")
		(25 "Edge.Cuts" user "Board Geometry/Outline")
		(27 "Margin" user)
		(31 "F.CrtYd" user "Package Geometry/Place Bound Top")
		(29 "B.CrtYd" user "Package Geometry/Place Bound Bottom")
		(35 "F.Fab" user "Ref Des/Assembly Top")
		(33 "B.Fab" user "Ref Des/Assembly Bottom")
	)
	(footprint ""
		(layer "F.Cu")
		(at 36.605718 -353.75723)
		(property "Reference" "PR704"
			(at 0 0 0)
			(layer "F.SilkS")
			(hide yes)
			(effects
				(font
					(size 1.27 1.27)
				)
			)
		)
		(property "Value" ""
			(at 0 0 0)
			(layer "F.Fab")
			(effects
				(font
					(size 1.27 1.27)
				)
			)
		)
		(duplicate_pad_numbers_are_jumpers no)
		(fp_line
			(start -0.7874 -0.4064)
			(end 0.7874 -0.4064)
			(stroke
				(width 0.1524)
				(type default)
			)
			(layer "F.SilkS")
		)
		(fp_line
			(start -0.7874 0.4064)
			(end -0.7874 -0.4064)
			(stroke
				(width 0.1524)
				(type default)
			)
			(layer "F.SilkS")
		)
		(fp_line
			(start 0.7874 -0.4064)
			(end 0.7874 0.4064)
			(stroke
				(width 0.1524)
				(type default)
			)
			(layer "F.SilkS")
		)
		(fp_line
			(start 0.7874 0.4064)
			(end -0.7874 0.4064)
			(stroke
				(width 0.1524)
				(type default)
			)
			(layer "F.SilkS")
		)
		(fp_line
			(start -0.67945 -0.305054)
			(end -0.12065 -0.305054)
			(stroke
				(width 0.1)
				(type default)
			)
			(layer "F.Fab")
		)
		(fp_line
			(start -0.67945 0.3048)
			(end -0.67945 -0.305054)
			(stroke
				(width 0.1)
				(type default)
			)
			(layer "F.Fab")
		)
		(fp_line
			(start -0.12065 -0.305054)
			(end -0.12065 -0.2794)
			(stroke
				(width 0.1)
				(type default)
			)
			(layer "F.Fab")
		)
		(fp_line
			(start -0.12065 -0.2794)
			(end 0.12065 -0.2794)
			(stroke
				(width 0.1)
				(type default)
			)
			(layer "F.Fab")
		)
		(fp_line
			(start -0.12065 0.2794)
			(end -0.12065 0.3048)
			(stroke
				(width 0.1)
				(type default)
			)
			(layer "F.Fab")
		)
		(fp_line
			(start -0.12065 0.3048)
			(end -0.67945 0.3048)
			(stroke
				(width 0.1)
				(type default)
			)
			(layer "F.Fab")
		)
		(fp_line
			(start 0.120396 0.2794)
			(end -0.12065 0.2794)
			(stroke
				(width 0.1)
				(type default)
			)
			(layer "F.Fab")
		)
		(fp_line
			(start 0.120396 0.3048)
			(end 0.120396 0.2794)
			(stroke
				(width 0.1)
				(type default)
			)
			(layer "F.Fab")
		)
		(fp_line
			(start 0.12065 -0.3048)
			(end 0.67945 -0.3048)
			(stroke
				(width 0.1)
				(type default)
			)
			(layer "F.Fab")
		)
		(fp_line
			(start 0.12065 -0.2794)
			(end 0.12065 -0.3048)
			(stroke
				(width 0.1)
				(type default)
			)
			(layer "F.Fab")
		)
		(fp_line
			(start 0.67945 -0.3048)
			(end 0.67945 0.3048)
			(stroke
				(width 0.1)
				(type default)
			)
			(layer "F.Fab")
		)
		(fp_line
			(start 0.67945 0.3048)
			(end 0.120396 0.3048)
			(stroke
				(width 0.1)
				(type default)
			)
			(layer "F.Fab")
		)
		(pad "1" smd circle
			(at -0.40005 0)
			(size 0 0)
			(layers "F.Cu" "F.Mask" "F.Paste")
			(net "P3V3")
		)
		(pad "2" smd circle
			(at 0.40005 0)
			(size 0 0)
			(layers "F.Cu" "F.Mask" "F.Paste")
			(net "PVCCFA_EHV_FIVRA_CPU1_PVCC2")
		)
	)
	(footprint ""
		(layer "F.Cu")
		(at 46.350428 -102.888034)
		(property "Reference" "C1757"
			(at 0 0 0)
			(layer "F.SilkS")
			(hide yes)
			(effects
				(font
					(size 1.27 1.27)
				)
			)
		)
		(property "Value" ""
			(at 0 0 0)
			(layer "F.Fab")
			(effects
				(font
					(size 1.27 1.27)
				)
			)
		)
		(duplicate_pad_numbers_are_jumpers no)
		(fp_line
			(start -0.7874 -0.4064)
			(end 0.7874 -0.4064)
			(stroke
				(width 0.1524)
				(type default)
			)
			(layer "F.SilkS")
		)
		(fp_line
			(start -0.7874 0.4064)
			(end -0.7874 -0.4064)
			(stroke
				(width 0.1524)
				(type default)
			)
			(layer "F.SilkS")
		)
		(fp_line
			(start 0.7874 -0.4064)
			(end 0.7874 0.4064)
			(stroke
				(width 0.1524)
				(type default)
			)
			(layer "F.SilkS")
		)
		(fp_line
			(start 0.7874 0.4064)
			(end -0.7874 0.4064)
			(stroke
				(width 0.1524)
				(type default)
			)
			(layer "F.SilkS")
		)
		(fp_line
			(start -0.67945 -0.305054)
			(end -0.12065 -0.305054)
			(stroke
				(width 0.1)
				(type default)
			)
			(layer "F.Fab")
		)
		(fp_line
			(start -0.67945 0.3048)
			(end -0.67945 -0.305054)
			(stroke
				(width 0.1)
				(type default)
			)
			(layer "F.Fab")
		)
		(fp_line
			(start -0.12065 -0.305054)
			(end -0.12065 -0.2794)
			(stroke
				(width 0.1)
				(type default)
			)
			(layer "F.Fab")
		)
		(fp_line
			(start -0.12065 -0.2794)
			(end 0.12065 -0.2794)
			(stroke
				(width 0.1)
				(type default)
			)
			(layer "F.Fab")
		)
		(fp_line
			(start -0.12065 0.2794)
			(end -0.12065 0.3048)
			(stroke
				(width 0.1)
				(type default)
			)
			(layer "F.Fab")
		)
		(fp_line
			(start -0.12065 0.3048)
			(end -0.67945 0.3048)
			(stroke
				(width 0.1)
				(type default)
			)
			(layer "F.Fab")
		)
		(fp_line
			(start 0.120396 0.2794)
			(end -0.12065 0.2794)
			(stroke
				(width 0.1)
				(type default)
			)
			(layer "F.Fab")
		)
		(fp_line
			(start 0.120396 0.3048)
			(end 0.120396 0.2794)
			(stroke
				(width 0.1)
				(type default)
			)
			(layer "F.Fab")
		)
		(fp_line
			(start 0.12065 -0.3048)
			(end 0.67945 -0.3048)
			(stroke
				(width 0.1)
				(type default)
			)
			(layer "F.Fab")
		)
		(fp_line
			(start 0.12065 -0.2794)
			(end 0.12065 -0.3048)
			(stroke
				(width 0.1)
				(type default)
			)
			(layer "F.Fab")
		)
		(fp_line
			(start 0.67945 -0.3048)
			(end 0.67945 0.3048)
			(stroke
				(width 0.1)
				(type default)
			)
			(layer "F.Fab")
		)
		(fp_line
			(start 0.67945 0.3048)
			(end 0.120396 0.3048)
			(stroke
				(width 0.1)
				(type default)
			)
			(layer "F.Fab")
		)
		(pad "1" smd circle
			(at -0.40005 0)
			(size 0 0)
			(layers "F.Cu" "F.Mask" "F.Paste")
			(net "P3V3_MAX11617_VDD")
		)
		(pad "2" smd circle
			(at 0.40005 0)
			(size 0 0)
			(layers "F.Cu" "F.Mask" "F.Paste")
			(net "GND")
		)
	)
)
